# T6G (Grand Teton) — schematic parts with pin connectivity, parts 3494–3662 of 8303; source: Cadence DE-HDL packaged netlist (pstxprt.dat, pstxnet.dat, pstchip.dat)

PC2155  Q_CAP  0.047UF 25V 10% X7R  pkg C0402  page 135 : 1 = P12V_OCP_SS_1 ; 2 = GND
PC2156  Q_CAP  100NF 50V 10% X7R  pkg C0402  page 135 : 1 = P12V_OCP_IMON_1 ; 2 = GND
PC2157  Q_CAP  39PF 50V 5% NPO  pkg 0402  page 135 : 1 = P3V3_OCP_MODE_1 ; 2 = GND
PC2158  Q_CAP  2.2UF 16V 20% X7R  pkg C0603  page 135 : 1 = P12V_OCP_AVIN_PD_1 ; 2 = GND
PC2159  Q_CAP  1UF 25V 10% X6S  pkg C0402  page 135 : 1 = P3V3_AUX ; 2 = GND
PC2160  Q_CAP  0.1UF 25V 10% X7R  pkg 0402  page 135 : 1 = P12V_OCP_SFF ; 2 = GND
PC2161  Q_CAP  0.068UF 16V 10% X7R  pkg 0402  page 135 : 1 = P3V3_OCP_DVDT_1 ; 2 = GND
PC2162  Q_CAP  100PF 50V 5% X7R  pkg 0402  page 135 : 1 = P3V3_OCP_GATE_1 ; 2 = GND
PC2163  Q_CAP  10UF 16V 10% X6S  pkg C0805  page 135 : 1 = P3V3_OCP_SFF_R ; 2 = GND
PC2164  Q_CAP  0.22UF 16V 10% X7R  pkg 0402  page 141 : 1 = P12V_OCP_TIMER_2 ; 2 = GND
PC2165  Q_CAP  1UF 25V 10% X6S  pkg C0402  page 141 : 1 = P12V_AUX ; 2 = GND
PC2166  Q_CAP  0.047UF 25V 10% X7R  pkg C0402  page 141 : 1 = P12V_OCP_SS_2 ; 2 = GND
PC2167  Q_CAP  100PF 50V 5% NPO  pkg 0402  page 141 : 1 = P12V_OCP_IMON_2 ; 2 = GND
PC2168  Q_CAP  39PF 50V 5% NPO  pkg 0402  page 141 : 1 = P3V3_OCP_MODE_2 ; 2 = GND
PC2169  Q_CAP  1UF 25V 10% X6S  pkg C0402  page 141 : 1 = P3V3_AUX ; 2 = GND
PC2173  Q_CAP  10UF 16V 10% X6S  pkg C0805  page 141 : 1 = P3V3_OCP_V3_2_R ; 2 = GND
PC2174  Q_CAP  0.1UF 25V 10% X7R  pkg 0402  page 141 : 1 = P12V_OCP_V3_2 ; 2 = GND
PC2181  Q_CAP  1UF 25V 10% X6S  pkg C0402  page 263 : 1 = HSC_VDD_R_2 ; 2 = AGND_HSC
PC2182  Q_CAP  220PF 50V 10% X7R  pkg 0402  page 263 : 1 = HSC_ON ; 2 = AGND_HSC
PC2183  Q_CAP  220PF 50V 10% EMPTY  pkg 0402  page 263 : 1 = HSC_ON ; 2 = AGND_HSC
PC2184  Q_CAP  0.068UF 16V 10% X7R  pkg 0402  page 263 : 1 = HSC_SS ; 2 = AGND_HSC
PC2185  Q_CAP  0.068UF 16V 10% X7R  pkg 0402  page 263 : 1 = HSC_SS ; 2 = AGND_HSC
PC2186  Q_CAP  1UF 25V 10% X6S  pkg C0402  page 262 : 1 = HSC_VDD_R ; 2 = AGND_HSC
PC2187  Q_CAP  1UF 25V 10% X6S  pkg C0402  page 262 : 1 = HSC_VDD_R ; 2 = AGND_HSC
PC2188  Q_CAP  1UF 25V 10% X6S  pkg C0402  page 262 : 1 = P12V_PSU ; 2 = GND
PC2189  Q_CAP  0.01UF 50V 10% X7R  pkg C0402  page 262 : 1 = HSC_VSENSE ; 2 = AGND_HSC
PC2190  Q_CAP  0.01UF 50V 10% X7R  pkg C0402  page 262 : 1 = HSC_VOSEN ; 2 = AGND_HSC
PC2191  Q_CAP  0.068UF 16V 10% X7R  pkg 0402  page 262 : 1 = HSC_SS ; 2 = AGND_HSC
PC2192  Q_CAP  0.001UF 50V 10% X7R  pkg C0402  page 262 : 1 = HSC_VTEMP ; 2 = AGND_HSC
PC2193  Q_CAP  0.047UF 25V 10% X7R  pkg C0402  page 262 : 1 = HSC_IMON ; 2 = AGND_HSC
PC2196  Q_CAP  0.22UF 16V 10% X7R  pkg 0402  page 147 : 1 = P12V_E1S_TIMER_0 ; 2 = GND
PC2197  Q_CAP  39PF 50V 5% NPO  pkg 0402  page 147 : 1 = P3V3_E1S_MODE_0 ; 2 = GND
PC2198  Q_CAP  1UF 25V 10% X6S  pkg C0402  page 147 : 1 = P12V_AUX ; 2 = GND
PC2200  Q_CAP  1UF 25V 10% X6S  pkg C0402  page 147 : 1 = P3V3_AUX ; 2 = GND
PC2201  Q_CAP  0.068UF 16V 10% X7R  pkg 0402  page 147 : 1 = P3V3_E1S_DVDT_0 ; 2 = GND
PC2202  Q_CAP  100NF 50V 10% X7R  pkg C0402  page 147 : 1 = P12V_E1S_IMON_0 ; 2 = GND
PC2203  Q_CAP  100PF 50V 5% X7R  pkg 0402  page 147 : 1 = P3V3_E1S_GATE_0_PU293 ; 2 = GND
PC2204  Q_CAP  10UF 16V 10% X6S  pkg C0805  page 147 : 1 = P3V3_E1S_0_R ; 2 = GND
PC2205  Q_CAP  2.2UF 16V 20% X7R  pkg C0603  page 147 : 1 = P12V_E1S_AVIN_PD_0 ; 2 = GND
PC2206  Q_CAP  0.1UF 25V 10% X7R  pkg 0402  page 147 : 1 = P12V_E1S_0 ; 2 = GND
PC2207  Q_CAP  1UF 25V 10% X6S  pkg C0402  page 146 : 1 = P12V_AUX ; 2 = GND
PC2208  Q_CAP  1UF 25V 10% X6S  pkg C0402  page 146 : 1 = P3V3_AUX ; 2 = GND
PC2209  Q_CAP  1UF 25V 10% X6S  pkg C0402  page 146 : 1 = P12V_E1S_VCC_0 ; 2 = GND
PC2210  Q_CAP  1UF 25V 10% X6S  pkg C0402  page 146 : 1 = P3V3_E1S_VCC_0 ; 2 = GND
PC2211  Q_CAP  1UF 25V 10% X6S  pkg C0402  page 146 : 1 = GND ; 2 = P12V_E1S_REG_0
PC2212  Q_CAP  1UF 25V 10% X6S  pkg C0402  page 146 : 1 = GND ; 2 = P3V3_E1S_REG_0
PC2213  Q_CAP  0.01UF 50V 10% EMPTY  pkg C0402  page 146 : 1 = P3V3_E1S_0_R ; 2 = P3V3_E1S_GATE_0
PC2214  Q_CAP  0.01UF 50V 10% EMPTY  pkg C0402  page 146 : 1 = P12V_E1S_0 ; 2 = P12V_E1S_GATE_0
PC2215  Q_CAP  3900PF 50V 10% X7R  pkg C0402  page 146 : 1 = P12V_E1S_GATE_0 ; 2 = GND
PC2216  Q_CAP  6800PF 50V 10% X7R  pkg C0402  page 146 : 1 = P3V3_E1S_GATE_0 ; 2 = GND
PC2217  Q_CAP  0.1UF 25V 10% X7R  pkg 0402  page 146 : 1 = P12V_E1S_0 ; 2 = GND
PC2218  Q_CAP  0.1UF 25V 10% X7R  pkg 0402  page 146 : 1 = P3V3_E1S_0_R ; 2 = GND
PC2219  Q_CAP  10UF 16V 10% X6S  pkg C0805  page 146 : 1 = P12V_E1S_0 ; 2 = GND
PC2220  Q_CAP  10UF 16V 10% X6S  pkg C0805  page 146 : 1 = P3V3_E1S_0_R ; 2 = GND
PC2223  Q_CAP  1UF 25V 10% X6S  pkg C0402  page 264 : 1 = HSC_VDD_R_4 ; 2 = AGND_HSC
PC2224  Q_CAP  220PF 50V 10% EMPTY  pkg 0402  page 264 : 1 = HSC_ON ; 2 = AGND_HSC
PC2225  Q_CAP  220PF 50V 10% EMPTY  pkg 0402  page 264 : 1 = HSC_ON ; 2 = AGND_HSC
PC2226  Q_CAP  0.068UF 16V 10% X7R  pkg 0402  page 264 : 1 = HSC_SS ; 2 = AGND_HSC
PC2227  Q_CAP  0.068UF 16V 10% X7R  pkg 0402  page 264 : 1 = HSC_SS ; 2 = AGND_HSC
PC2229  Q_CAP  0.22UF 16V 10% X7R  pkg 0402  page 152 : 1 = P12V_SCM_TIMER ; 2 = GND
PC2230  Q_CAP  1UF 25V 10% X6S  pkg C0402  page 152 : 1 = P12V_AUX ; 2 = GND
PC2231  Q_CAP  1UF 25V 10% X6S  pkg C0402  page 152 : 1 = P12V_AUX ; 2 = GND
PC2232  Q_CAP  0.047UF 25V 10% X7R  pkg C0402  page 152 : 1 = P12V_SCM_SS ; 2 = GND
PC2233  Q_CAP  1UF 25V 10% X6S  pkg C0402  page 152 : 1 = P12V_SCM_VCC ; 2 = GND
PC2234  Q_CAP  1UF 25V 10% X6S  pkg C0402  page 152 : 1 = GND ; 2 = P12V_SCM_REG
PC2235  Q_CAP  100NF 50V 10% X7R  pkg C0402  page 152 : 1 = P12V_SCM_IMON ; 2 = GND
PC2236  Q_CAP  0.01UF 50V 10% EMPTY  pkg C0402  page 152 : 1 = P12V_SCM_R ; 2 = P12V_SCM_GATE
PC2237  Q_CAP  3900PF 50V 10% X7R  pkg C0402  page 152 : 1 = P12V_SCM_GATE ; 2 = GND
PC2238  Q_CAP  0.1UF 25V 10% X7R  pkg 0402  page 152 : 1 = P12V_SCM_R ; 2 = GND
PC2239  Q_CAP  2.2UF 16V 20% X7R  pkg C0603  page 152 : 1 = P12V_SCM_AVIN_PD ; 2 = GND
PC2240  Q_CAP  10UF 16V 10% X6S  pkg C0805  page 152 : 1 = P12V_SCM_R ; 2 = GND
PC2241  Q_CAP  0.1UF 25V 10% X7R  pkg 0402  page 152 : 1 = P12V_SCM_R ; 2 = GND
PC2242  Q_CAP  22UF 16V 20% X6S  pkg C0805  page 152 : 1 = P12V_SCM_R ; 2 = GND
PC2260  Q_CAP  22UF 16V 20% X6S  pkg C0805  page 190 : 1 = SW_P3V3_AUX_FLT ; 2 = GND
PC2261  Q_CAP  22UF 16V 20% X6S  pkg C0805  page 190 : 1 = SW_P3V3_AUX_FLT ; 2 = GND
PC2262  Q_CAP  22UF 16V 20% X6S  pkg C0805  page 190 : 1 = SW_P3V3_AUX_FLT ; 2 = GND
PC2263  Q_CAP  22UF 16V 20% X6S  pkg C0805  page 190 : 1 = SW_P3V3_AUX_FLT ; 2 = GND
PC2280  Q_CAP  10UF 16V 10% X6S  pkg C0805  page 146 : 1 = P12V_E1S_0 ; 2 = GND
PC2281  Q_CAP  0.047UF 25V 10% X7R  pkg C0402  page 147 : 1 = P12V_E1S_SS_0 ; 2 = GND
PC2340  Q_CAP  560PF 50V 10% X7R  pkg C0402  page 152 : 1 = P12V_SCM_ISET_R ; 2 = GND
PC2341  Q_CAP  560PF 50V 10% X7R  pkg C0402  page 147 : 1 = P12V_E1S_ISET_0_R ; 2 = GND
PC2342  Q_CAP  22UF 16V 20% X6S  pkg C0805  page 190 : 1 = SW_P3V3_AUX_FLT ; 2 = GND
PC2343  Q_CAP  22UF 16V 20% X6S  pkg C0805  page 190 : 1 = SW_P3V3_AUX_FLT ; 2 = GND
PC2344  Q_CAP  22UF 16V 20% X6S  pkg C0805  page 190 : 1 = SW_P3V3_AUX_FLT ; 2 = GND
PC2347  Q_CAP  1NF 50V 10% EMPTY  pkg 0402  page 263 : 1 = HSC_OCREF ; 2 = AGND_HSC
PC2348  Q_CAP  1NF 50V 10% EMPTY  pkg 0402  page 263 : 1 = HSC_OCREF ; 2 = AGND_HSC
PC2349  Q_CAP  1NF 50V 10% EMPTY  pkg 0402  page 264 : 1 = HSC_OCREF ; 2 = AGND_HSC
PC2350  Q_CAP  1NF 50V 10% EMPTY  pkg 0402  page 264 : 1 = HSC_OCREF ; 2 = AGND_HSC
PC3272  Q_CAP  1UF 25V 10% X6S  pkg C0402  page 264 : 1 = HSC_VDD_R_3 ; 2 = AGND_HSC
PC4056  Q_CAP  3900PF 50V 10% X7R  pkg C0402  page 134 : 1 = P12V_OCP_GATE_1 ; 2 = GND
PC5328  Q_CAP  1UF 25V 10% X6S  pkg C0402  page 134 : 1 = P3V3_AUX ; 2 = GND
PC6000  Q_CAP  0.1UF 25V 10% X6S  pkg C0402  page 192 : 1 = P12V_AUX ; 2 = GND
PC6001  Q_CAP  0.1UF 25V 10% X6S  pkg C0402  page 209 : 1 = P12V_AUX ; 2 = GND
PC6002  Q_CAP  0.1UF 25V 10% X7R  pkg 0402  page 226 : 1 = P12V_AUX ; 2 = GND
PC6003  Q_CAP  0.1UF 25V 10% X7R  pkg 0402  page 208 : 1 = P12V_AUX ; 2 = GND
PC6004  Q_CAP  0.1UF 25V 10% X7R  pkg 0402  page 211 : 1 = P12V_AUX ; 2 = GND
PC6005  Q_CAP  0.01UF 25V 10% EMPTY  pkg C0402  page 209 : 1 = PVDD18_S5_P0_FB_RC ; 2 = PVDD18_S5_P0_RGND
PC6006  Q_CAP  0.01UF 25V 10% EMPTY  pkg C0402  page 226 : 1 = PVDD18_S5_P1_FB_RC ; 2 = PVDD18_SS_P1_RGND
PC6007  Q_CAP  0.1UF 25V 10% X7R  pkg 0402  page 215 : 1 = P12V_AUX ; 2 = GND
PC6008  Q_CAP  1UF 25V 10% X6S  pkg C0402  page 269 : 1 = P1V8_AUX_VCC ; 2 = GND
PC6009  Q_CAP  1UF 25V 10% X6S  pkg C0402  page 270 : 1 = P1V2_AUX_VCC ; 2 = GND
PC6010  Q_CAP  1UF 25V 10% X6S  pkg C0402  page 269 : 1 = SW_P12V_AUX_P1V8_AUX_FLT ; 2 = GND
PC6011  Q_CAP  1UF 25V 10% X6S  pkg C0402  page 270 : 1 = SW_P12V_AUX_P1V2_AUX_FLT ; 2 = GND
PC6012  Q_CAP  22UF 16V 20% X6S  pkg C0805  page 269 : 1 = SW_P12V_AUX_P1V8_AUX_FLT ; 2 = GND
PC6013  Q_CAP  22UF 16V 20% X6S  pkg C0805  page 270 : 1 = SW_P12V_AUX_P1V2_AUX_FLT ; 2 = GND
PC6014  Q_CAP  22UF 16V 20% X6S  pkg C0805  page 269 : 1 = SW_P12V_AUX_P1V8_AUX_FLT ; 2 = GND
PC6015  Q_CAP  22UF 16V 20% X6S  pkg C0805  page 270 : 1 = SW_P12V_AUX_P1V2_AUX_FLT ; 2 = GND
PC6016  Q_CAP  3300PF 50V 10% X7R  pkg 0402  page 270 : 1 = P1V2_AUX_REF ; 2 = GND
PC6017  Q_CAP  0.22UF 25V 10% X7R  pkg C0402  page 270 : 1 = SW_P1V2_AUX_BT_R ; 2 = SW_P1V2_AUX_PH
PC6018  Q_CAP  22UF 4V 20% X6S  pkg C0805  page 270 : 1 = P1V2_AUX ; 2 = GND
PC6019  Q_CAP  330PF 50V 10% X7R  pkg 0402  page 269 : 1 = P1V8_AUX_FB ; 2 = P1V8_AUX
PC6020  Q_CAP  100NF 50V 10% X7R  pkg C0402  page 269 : 1 = P12V_AUX ; 2 = GND
PC6021  Q_CAP  100NF 50V 10% X7R  pkg C0402  page 269 : 1 = P1V8_AUX ; 2 = GND
PC6022  Q_CAP  100NF 50V 10% X7R  pkg C0402  page 270 : 1 = P1V2_AUX ; 2 = GND
PC6023  Q_CAP  100NF 50V 10% X7R  pkg C0402  page 270 : 1 = P12V_AUX ; 2 = GND
PC6024  Q_CAP  22UF 4V 20% X6S  pkg C0805  page 270 : 1 = P1V2_AUX ; 2 = GND
PC6025  Q_CAP  22UF 4V 20% X6S  pkg C0805  page 270 : 1 = P1V2_AUX ; 2 = GND
PC6026  Q_CAP  22UF 4V 20% X6S  pkg C0805  page 270 : 1 = P1V2_AUX ; 2 = GND
PC6500  Q_CAP  0.1UF 25V 10% X6S  pkg C0402  page 360 : 1 = P12V_AUX ; 2 = GND
PC6501  Q_CAP  22UF 16V 20% X6S  pkg C0805  page 360 : 1 = SW_P12V_AUX_P1V8_RETIMER_CPU0_FLT ; 2 = GND
PC6502  Q_CAP  22UF 16V 20% X6S  pkg C0805  page 360 : 1 = SW_P12V_AUX_P1V8_RETIMER_CPU0_FLT ; 2 = GND
PC6503  Q_CAP  22UF 16V 20% X6S  pkg C0805  page 360 : 1 = SW_P12V_AUX_P1V8_RETIMER_CPU0_FLT ; 2 = GND
PC6504  Q_CAP  22UF 16V 20% X6S  pkg C0805  page 360 : 1 = SW_P12V_AUX_P1V8_RETIMER_CPU0_FLT ; 2 = GND
PC6505  Q_CAP  1UF 25V 10% X6S  pkg C0402  page 360 : 1 = SW_P12V_AUX_P1V8_RETIMER_CPU0_FLT ; 2 = GND
PC6506  Q_CAP  1UF 25V 10% X6S  pkg C0402  page 360 : 1 = P1V8_RETIMER_CPU0_VCC ; 2 = GND
PC6507  Q_CAP  0.22UF 16V 10% X7R  pkg 0402  page 360 : 1 = SW_P1V8_RETIMER_CPU0_BST_R ; 2 = SW_P1V8_RETIMER_CPU0_SW
PC6508  Q_CAP  22UF 4V 20% X6S  pkg C0805  page 360 : 1 = P1V8_CPU0_RT_1D ; 2 = GND
PC6509  Q_CAP  22UF 4V 20% X6S  pkg C0805  page 360 : 1 = P1V8_CPU0_RT_1D ; 2 = GND
PC6510  Q_CAP  22UF 4V 20% X6S  pkg C0805  page 360 : 1 = P1V8_CPU0_RT_1D ; 2 = GND
PC6511  Q_CAP  22UF 4V 20% X6S  pkg C0805  page 360 : 1 = P1V8_CPU0_RT_1D ; 2 = GND
PC6512  Q_CAP  22UF 4V 20% X6S  pkg C0805  page 360 : 1 = P1V8_CPU0_RT_1D ; 2 = GND
PC6513  Q_CAPP  390UF 2.5V 20% ALUM  pkg SMLF  page 360 : 1 = P1V8_CPU0_RT_1D ; 2 = GND
PC6514  Q_CAP  0.1UF 25V 10% X7R  pkg 0402  page 360 : 1 = P1V8_CPU0_RT_1D ; 2 = GND
PC6515  Q_CAP  150PF 50V 5% NPO  pkg 0402  page 360 : 1 = P1V8_RETIMER_CPU0_FB ; 2 = P1V8_CPU0_RT_1D
PC6518  Q_CAP  0.1UF 25V 10% X7R  pkg 0402  page 360 : 1 = P1V8_RETIMER_CPU0_REF ; 2 = GND
PC6519  Q_CAP  0.1UF 25V 10% X6S  pkg C0402  page 361 : 1 = P12V_AUX ; 2 = GND
PC6520  Q_CAP  22UF 16V 20% X6S  pkg C0805  page 361 : 1 = SW_P12V_AUX_P1V8_RETIMER_CPU1_FLT ; 2 = GND
PC6521  Q_CAP  22UF 16V 20% X6S  pkg C0805  page 361 : 1 = SW_P12V_AUX_P1V8_RETIMER_CPU1_FLT ; 2 = GND
PC6522  Q_CAP  22UF 16V 20% X6S  pkg C0805  page 361 : 1 = SW_P12V_AUX_P1V8_RETIMER_CPU1_FLT ; 2 = GND
PC6523  Q_CAP  22UF 16V 20% X6S  pkg C0805  page 361 : 1 = SW_P12V_AUX_P1V8_RETIMER_CPU1_FLT ; 2 = GND
PC6524  Q_CAP  1UF 25V 10% X6S  pkg C0402  page 361 : 1 = SW_P12V_AUX_P1V8_RETIMER_CPU1_FLT ; 2 = GND
PC6525  Q_CAP  1UF 25V 10% X6S  pkg C0402  page 361 : 1 = P1V8_RETIMER_CPU1_VCC ; 2 = GND
PC6526  Q_CAP  0.22UF 16V 10% X7R  pkg 0402  page 361 : 1 = SW_P1V8_RETIMER_CPU1_BST_R ; 2 = SW_P1V8_RETIMER_CPU1_SW
PC6527  Q_CAP  22UF 4V 20% X6S  pkg C0805  page 361 : 1 = P1V8_CPU1_RT_1D ; 2 = GND
PC6528  Q_CAP  22UF 4V 20% X6S  pkg C0805  page 361 : 1 = P1V8_CPU1_RT_1D ; 2 = GND
PC6529  Q_CAP  22UF 4V 20% X6S  pkg C0805  page 361 : 1 = P1V8_CPU1_RT_1D ; 2 = GND
PC6530  Q_CAP  22UF 4V 20% X6S  pkg C0805  page 361 : 1 = P1V8_CPU1_RT_1D ; 2 = GND
PC6531  Q_CAP  22UF 4V 20% X6S  pkg C0805  page 361 : 1 = P1V8_CPU1_RT_1D ; 2 = GND
PC6532  Q_CAPP  390UF 2.5V 20% ALUM  pkg SMLF  page 361 : 1 = P1V8_CPU1_RT_1D ; 2 = GND
PC6533  Q_CAP  0.1UF 25V 10% X7R  pkg 0402  page 361 : 1 = P1V8_CPU1_RT_1D ; 2 = GND
PC6534  Q_CAP  150PF 50V 5% NPO  pkg 0402  page 361 : 1 = P1V8_RETIMER_CPU1_FB ; 2 = P1V8_CPU1_RT_1D
PC6537  Q_CAP  0.1UF 25V 10% X7R  pkg 0402  page 361 : 1 = P1V8_RETIMER_CPU1_REF ; 2 = GND
PC6540  Q_CAP  3300PF 50V 10% X7R  pkg 0402  page 362 : 1 = P0V9_RETIMER_CPU0_SENSE_R_P ; 2 = P0V9_RETIMER_CPU0_SENSE_SH_N
PC6543  Q_CAP  100NF 50V 10% X7R  pkg C0402  page 364 : 1 = P0V9_RETIMER_CPU1_VCC ; 2 = GND
PC6544  Q_CAP  1UF 16V 10% X6S  pkg C0402  page 364 : 1 = P0V9_RETIMER_CPU1_VCC ; 2 = GND
PC6545  Q_CAP  1UF 16V 10% X6S  pkg C0402  page 364 : 1 = PV09_RETIMER_CPU1_VCCS ; 2 = GND
PC6546  Q_CAP  10UF 6.3V 20% X6S  pkg C0402  page 364 : 1 = PV09_RETIMER_CPU1_VCCS ; 2 = GND
PC6550_09P0_1  Q_CAP  2.2UF 10V 10% X6S  pkg C0402  page 363 : 1 = P0V9_RETIMER_CPU0_PVCC ; 2 = GND
PC6551_09P0_2  Q_CAP  2.2UF 10V 10% X6S  pkg C0402  page 363 : 1 = P0V9_RETIMER_CPU0_PVCC ; 2 = GND
PC6552  Q_CAP  2.2UF 10V 10% X6S  pkg C0402  page 363 : 1 = P0V9_RETIMER_CPU0_VCC1 ; 2 = GND
PC6553_1  Q_CAP  100NF 50V 10% X7R  pkg C0402  page 363 : 1 = PV09_RETIMER_CPU0_VCCS ; 2 = GND
PC6554_1  Q_CAP  1UF 25V 10% X6S  pkg C0402  page 363 : 1 = SW_P12V_AUX_P0V9_RETIMER_CPU0_FLT ; 2 = GND
PC6555_1  Q_CAP  3300PF 50V 10% X7R  pkg 0402  page 363 : 1 = SW_P12V_AUX_P0V9_RETIMER_CPU0_FLT ; 2 = GND
PC6556_1  Q_CAP  22UF 16V 20% X6S  pkg C0805  page 363 : 1 = SW_P12V_AUX_P0V9_RETIMER_CPU0_FLT ; 2 = GND
PC6557_1  Q_CAP  22UF 16V 20% X6S  pkg C0805  page 363 : 1 = SW_P12V_AUX_P0V9_RETIMER_CPU0_FLT ; 2 = GND
PC6558_1  Q_CAP  22UF 16V 20% X6S  pkg C0805  page 363 : 1 = SW_P12V_AUX_P0V9_RETIMER_CPU0_FLT ; 2 = GND
PC6559_1  Q_CAP  22UF 16V 20% X6S  pkg C0805  page 363 : 1 = SW_P12V_AUX_P0V9_RETIMER_CPU0_FLT ; 2 = GND
PC6560  Q_CAP  22UF 16V 20% X6S  pkg C0805  page 363 : 1 = SW_P12V_AUX_P0V9_RETIMER_CPU0_FLT ; 2 = GND
PC6561  Q_CAPP  100UF 16V 20% OSCON  pkg SMLF  page 363 : 1 = SW_P12V_AUX_P0V9_RETIMER_CPU0_FLT ; 2 = GND
